# S9S_MB_2U (Grand Teton) — schematic netlist excerpt (pin names and nets, part order shuffled) for the footprints in the layout excerpt that follows; sources: Cadence DE-HDL packaged netlist, KiCad conversion of 03242023_DA0F0TMBIJ0_F0T_Motherboard_J_brd_V01_OCP.brd

C985  Q_CAP  10UF 6.3V 20% X6S  pkg C0402  page 74 : A = PVCCIN_CPU0 ; B = GND
R564  Q_RES  22 1% CHIP  pkg 0402LF  page 209 : A = CLK_100M_OCP_SFF_0_R_DN ; B = CLK_100M_OCP_SFF_0_DN

(kicad_pcb
	(version 20260206)
	(generator "pcbnew")
	(generator_version "10.0")
	(general
		(thickness 1.6)
		(legacy_teardrops no)
	)
	(paper "A4")
	(title_block
		(title "03242023_DA0F0TMBIJ0_F0T_Motherboard_J_brd_V01_OCP.brd")
		(comment 1 "Grand Teton / footprints 2120-2121 of 6105")
	)
	(layers
		(0 "F.Cu" signal "TOP")
		(4 "In1.Cu" signal "GND")
		(6 "In2.Cu" signal "IN1")
		(8 "In3.Cu" signal "GND1")
		(10 "In4.Cu" signal "IN2")
		(12 "In5.Cu" signal "GND2")
		(14 "In6.Cu" signal "IN3")
		(16 "In7.Cu" signal "GND3")
		(18 "In8.Cu" signal "VCC")
		(20 "In9.Cu" signal "VCC1")
		(22 "In10.Cu" signal "GND4")
		(24 "In11.Cu" signal "IN4")
		(26 "In12.Cu" signal "GND5")
		(28 "In13.Cu" signal "IN5")
		(30 "In14.Cu" signal "GND6")
		(32 "In15.Cu" signal "IN6")
		(34 "In16.Cu" signal "GND7")
		(2 "B.Cu" signal "BOTTOM")
		(9 "F.Adhes" user "F.Adhesive")
		(11 "B.Adhes" user "B.Adhesive")
		(13 "F.Paste" user "Package Geometry/Pastemask Top")
		(15 "B.Paste" user "Package Geometry/Pastemask Bottom")
		(5 "F.SilkS" user "Ref Des/Silkscreen Top")
		(7 "B.SilkS" user "Ref Des/Silkscreen Bottom")
		(1 "F.Mask" user "Board Geometry/Soldermask Top")
		(3 "B.Mask" user "Board Geometry/Soldermask Bottom")
		(17 "Dwgs.User" user "User.Drawings")
		(19 "Cmts.User" user "User.Comments")
		(21 "Eco1.User" user "User.Eco1")
		(23 "Eco2.User" user "User.Eco2")
		(25 "Edge.Cuts" user "Board Geometry/Outline")
		(27 "Margin" user)
		(31 "F.CrtYd" user "Package Geometry/Place Bound Top")
		(29 "B.CrtYd" user "Package Geometry/Place Bound Bottom")
		(35 "F.Fab" user "Ref Des/Assembly Top")
		(33 "B.Fab" user "Ref Des/Assembly Bottom")
	)
	(footprint ""
		(layer "F.Cu")
		(at 364.50143 -247.715024 90)
		(property "Reference" "C985"
			(at 0 0 90)
			(layer "F.SilkS")
			(hide yes)
			(effects
				(font
					(size 1.27 1.27)
				)
			)
		)
		(property "Value" ""
			(at 0 0 90)
			(layer "F.Fab")
			(effects
				(font
					(size 1.27 1.27)
				)
			)
		)
		(duplicate_pad_numbers_are_jumpers no)
		(fp_line
			(start 0.7874 -0.4064)
			(end 0.7874 0.4064)
			(stroke
				(width 0.1524)
				(type default)
			)
			(layer "F.SilkS")
		)
		(fp_line
			(start -0.7874 -0.4064)
			(end 0.7874 -0.4064)
			(stroke
				(width 0.1524)
				(type default)
			)
			(layer "F.SilkS")
		)
		(fp_line
			(start 0.7874 0.4064)
			(end -0.7874 0.4064)
			(stroke
				(width 0.1524)
				(type default)
			)
			(layer "F.SilkS")
		)
		(fp_line
			(start -0.7874 0.4064)
			(end -0.7874 -0.4064)
			(stroke
				(width 0.1524)
				(type default)
			)
			(layer "F.SilkS")
		)
		(fp_line
			(start -0.12065 -0.305054)
			(end -0.12065 -0.2794)
			(stroke
				(width 0.1)
				(type default)
			)
			(layer "F.Fab")
		)
		(fp_line
			(start -0.67945 -0.305054)
			(end -0.12065 -0.305054)
			(stroke
				(width 0.1)
				(type default)
			)
			(layer "F.Fab")
		)
		(fp_line
			(start 0.67945 -0.3048)
			(end 0.67945 0.3048)
			(stroke
				(width 0.1)
				(type default)
			)
			(layer "F.Fab")
		)
		(fp_line
			(start 0.12065 -0.3048)
			(end 0.67945 -0.3048)
			(stroke
				(width 0.1)
				(type default)
			)
			(layer "F.Fab")
		)
		(fp_line
			(start 0.12065 -0.2794)
			(end 0.12065 -0.3048)
			(stroke
				(width 0.1)
				(type default)
			)
			(layer "F.Fab")
		)
		(fp_line
			(start -0.12065 -0.2794)
			(end 0.12065 -0.2794)
			(stroke
				(width 0.1)
				(type default)
			)
			(layer "F.Fab")
		)
		(fp_line
			(start 0.120396 0.2794)
			(end -0.12065 0.2794)
			(stroke
				(width 0.1)
				(type default)
			)
			(layer "F.Fab")
		)
		(fp_line
			(start -0.12065 0.2794)
			(end -0.12065 0.3048)
			(stroke
				(width 0.1)
				(type default)
			)
			(layer "F.Fab")
		)
		(fp_line
			(start 0.67945 0.3048)
			(end 0.120396 0.3048)
			(stroke
				(width 0.1)
				(type default)
			)
			(layer "F.Fab")
		)
		(fp_line
			(start 0.120396 0.3048)
			(end 0.120396 0.2794)
			(stroke
				(width 0.1)
				(type default)
			)
			(layer "F.Fab")
		)
		(fp_line
			(start -0.12065 0.3048)
			(end -0.67945 0.3048)
			(stroke
				(width 0.1)
				(type default)
			)
			(layer "F.Fab")
		)
		(fp_line
			(start -0.67945 0.3048)
			(end -0.67945 -0.305054)
			(stroke
				(width 0.1)
				(type default)
			)
			(layer "F.Fab")
		)
		(pad "1" smd circle
			(at -0.40005 0 90)
			(size 0 0)
			(layers "F.Cu" "F.Mask" "F.Paste")
			(net "PVCCIN_CPU0")
		)
		(pad "2" smd circle
			(at 0.40005 0 90)
			(size 0 0)
			(layers "F.Cu" "F.Mask" "F.Paste")
			(net "GND")
		)
	)
	(footprint ""
		(layer "F.Cu")
		(at 228.760782 -126.383542 180)
		(property "Reference" "R564"
			(at 0 0 180)
			(layer "F.SilkS")
			(hide yes)
			(effects
				(font
					(size 1.27 1.27)
				)
			)
		)
		(property "Value" ""
			(at 0 0 180)
			(layer "F.Fab")
			(effects
				(font
					(size 1.27 1.27)
				)
			)
		)
		(duplicate_pad_numbers_are_jumpers no)
		(fp_line
			(start 0.7874 -0.4064)
			(end 0.7874 0.039878)
			(stroke
				(width 0.1524)
				(type default)
			)
			(layer "F.SilkS")
		)
		(fp_line
			(start 0.330962 0.4064)
			(end -0.433578 0.4064)
			(stroke
				(width 0.1524)
				(type default)
			)
			(layer "F.SilkS")
		)
		(fp_line
			(start -0.7874 0.029718)
			(end -0.7874 -0.4064)
			(stroke
				(width 0.1524)
				(type default)
			)
			(layer "F.SilkS")
		)
		(fp_line
			(start -0.7874 -0.4064)
			(end 0.7874 -0.4064)
			(stroke
				(width 0.1524)
				(type default)
			)
			(layer "F.SilkS")
		)
		(fp_line
			(start 0.67945 0.3048)
			(end 0.120396 0.3048)
			(stroke
				(width 0.1)
				(type default)
			)
			(layer "F.Fab")
		)
		(fp_line
			(start 0.67945 -0.3048)
			(end 0.67945 0.3048)
			(stroke
				(width 0.1)
				(type default)
			)
			(layer "F.Fab")
		)
		(fp_line
			(start 0.12065 -0.2794)
			(end 0.12065 -0.3048)
			(stroke
				(width 0.1)
				(type default)
			)
			(layer "F.Fab")
		)
		(fp_line
			(start 0.12065 -0.3048)
			(end 0.67945 -0.3048)
			(stroke
				(width 0.1)
				(type default)
			)
			(layer "F.Fab")
		)
		(fp_line
			(start 0.120396 0.3048)
			(end 0.120396 0.2794)
			(stroke
				(width 0.1)
				(type default)
			)
			(layer "F.Fab")
		)
		(fp_line
			(start 0.120396 0.2794)
			(end -0.12065 0.2794)
			(stroke
				(width 0.1)
				(type default)
			)
			(layer "F.Fab")
		)
		(fp_line
			(start -0.12065 0.3048)
			(end -0.67945 0.3048)
			(stroke
				(width 0.1)
				(type default)
			)
			(layer "F.Fab")
		)
		(fp_line
			(start -0.12065 0.2794)
			(end -0.12065 0.3048)
			(stroke
				(width 0.1)
				(type default)
			)
			(layer "F.Fab")
		)
		(fp_line
			(start -0.12065 -0.2794)
			(end 0.12065 -0.2794)
			(stroke
				(width 0.1)
				(type default)
			)
			(layer "F.Fab")
		)
		(fp_line
			(start -0.12065 -0.305054)
			(end -0.12065 -0.2794)
			(stroke
				(width 0.1)
				(type default)
			)
			(layer "F.Fab")
		)
		(fp_line
			(start -0.67945 0.3048)
			(end -0.67945 -0.305054)
			(stroke
				(width 0.1)
				(type default)
			)
			(layer "F.Fab")
		)
		(fp_line
			(start -0.67945 -0.305054)
			(end -0.12065 -0.305054)
			(stroke
				(width 0.1)
				(type default)
			)
			(layer "F.Fab")
		)
		(pad "1" smd circle
			(at -0.40005 0 180)
			(size 0 0)
			(layers "F.Cu" "F.Mask" "F.Paste")
			(net "CLK_100M_OCP_SFF_0_R_DN")
		)
		(pad "2" smd circle
			(at 0.40005 0 180)
			(size 0 0)
			(layers "F.Cu" "F.Mask" "F.Paste")
			(net "CLK_100M_OCP_SFF_0_DN")
		)
	)
)
